# T6G (Grand Teton) — schematic netlist excerpt (pin names and nets, part order shuffled) for the footprints in the layout excerpt that follows; sources: Cadence DE-HDL packaged netlist, KiCad conversion of 04192023_DAF0TMB3IC0_F0TG_MB_C_brd_V02_OCP.brd

PR3787  Q_RES  6.8K 1% CHIP  pkg 0402LF  page 134 : A = P12V_OCP_UV_1 ; B = P12V_OCP_OV_1
R1121  Q_RES  4.7K 5% CHIP  pkg 0201LF  page 309 : A = JTAG_TEST_MODE_RT_CPU0_P3 ; B = GND
R1119  Q_RES  4.7K 5% EMPTY  pkg 0201LF  page 309 : A = P1V8_CPU0_RT_1D ; B = TEST2_RT_CPU0_P3

(kicad_pcb
	(version 20260206)
	(generator "pcbnew")
	(generator_version "10.0")
	(general
		(thickness 1.6)
		(legacy_teardrops no)
	)
	(paper "A4")
	(title_block
		(title "04192023_DAF0TMB3IC0_F0TG_MB_C_brd_V02_OCP.brd")
		(comment 1 "Grand Teton / footprints 964-966 of 8354")
	)
	(layers
		(0 "F.Cu" signal "TOP")
		(4 "In1.Cu" signal "GND")
		(6 "In2.Cu" signal "IN1")
		(8 "In3.Cu" signal "GND1")
		(10 "In4.Cu" signal "IN2")
		(12 "In5.Cu" signal "GND2")
		(14 "In6.Cu" signal "IN3")
		(16 "In7.Cu" signal "GND3")
		(18 "In8.Cu" signal "VCC")
		(20 "In9.Cu" signal "VCC1")
		(22 "In10.Cu" signal "GND4")
		(24 "In11.Cu" signal "IN4")
		(26 "In12.Cu" signal "GND5")
		(28 "In13.Cu" signal "IN5")
		(30 "In14.Cu" signal "GND6")
		(32 "In15.Cu" signal "IN6")
		(34 "In16.Cu" signal "GND7")
		(2 "B.Cu" signal "BOTTOM")
		(9 "F.Adhes" user "F.Adhesive")
		(11 "B.Adhes" user "B.Adhesive")
		(13 "F.Paste" user "Package Geometry/Pastemask Top")
		(15 "B.Paste" user "Package Geometry/Pastemask Bottom")
		(5 "F.SilkS" user "Ref Des/Silkscreen Top")
		(7 "B.SilkS" user "Ref Des/Silkscreen Bottom")
		(1 "F.Mask" user "Board Geometry/Soldermask Top")
		(3 "B.Mask" user "Board Geometry/Soldermask Bottom")
		(17 "Dwgs.User" user "User.Drawings")
		(19 "Cmts.User" user "User.Comments")
		(21 "Eco1.User" user "User.Eco1")
		(23 "Eco2.User" user "User.Eco2")
		(25 "Edge.Cuts" user "Board Geometry/Outline")
		(27 "Margin" user)
		(31 "F.CrtYd" user "Package Geometry/Place Bound Top")
		(29 "B.CrtYd" user "Package Geometry/Place Bound Bottom")
		(35 "F.Fab" user "Ref Des/Assembly Top")
		(33 "B.Fab" user "Ref Des/Assembly Bottom")
	)
	(footprint ""
		(layer "F.Cu")
		(at 448.980052 -18.063464 -90)
		(property "Reference" "PR3787"
			(at 0 0 270)
			(layer "F.SilkS")
			(hide yes)
			(effects
				(font
					(size 1.27 1.27)
				)
			)
		)
		(property "Value" ""
			(at 0 0 270)
			(layer "F.Fab")
			(effects
				(font
					(size 1.27 1.27)
				)
			)
		)
		(duplicate_pad_numbers_are_jumpers no)
		(fp_line
			(start -0.7874 0.4064)
			(end -0.7874 -0.4064)
			(stroke
				(width 0.1524)
				(type default)
			)
			(layer "F.SilkS")
		)
		(fp_line
			(start 0.7874 0.4064)
			(end -0.7874 0.4064)
			(stroke
				(width 0.1524)
				(type default)
			)
			(layer "F.SilkS")
		)
		(fp_line
			(start -0.7874 -0.4064)
			(end 0.7874 -0.4064)
			(stroke
				(width 0.1524)
				(type default)
			)
			(layer "F.SilkS")
		)
		(fp_line
			(start 0.7874 -0.4064)
			(end 0.7874 0.4064)
			(stroke
				(width 0.1524)
				(type default)
			)
			(layer "F.SilkS")
		)
		(fp_line
			(start -0.67945 0.3048)
			(end -0.67945 -0.305054)
			(stroke
				(width 0.1)
				(type default)
			)
			(layer "F.Fab")
		)
		(fp_line
			(start -0.12065 0.3048)
			(end -0.67945 0.3048)
			(stroke
				(width 0.1)
				(type default)
			)
			(layer "F.Fab")
		)
		(fp_line
			(start 0.120396 0.3048)
			(end 0.120396 0.2794)
			(stroke
				(width 0.1)
				(type default)
			)
			(layer "F.Fab")
		)
		(fp_line
			(start 0.67945 0.3048)
			(end 0.120396 0.3048)
			(stroke
				(width 0.1)
				(type default)
			)
			(layer "F.Fab")
		)
		(fp_line
			(start -0.12065 0.2794)
			(end -0.12065 0.3048)
			(stroke
				(width 0.1)
				(type default)
			)
			(layer "F.Fab")
		)
		(fp_line
			(start 0.120396 0.2794)
			(end -0.12065 0.2794)
			(stroke
				(width 0.1)
				(type default)
			)
			(layer "F.Fab")
		)
		(fp_line
			(start -0.12065 -0.2794)
			(end 0.12065 -0.2794)
			(stroke
				(width 0.1)
				(type default)
			)
			(layer "F.Fab")
		)
		(fp_line
			(start 0.12065 -0.2794)
			(end 0.12065 -0.3048)
			(stroke
				(width 0.1)
				(type default)
			)
			(layer "F.Fab")
		)
		(fp_line
			(start 0.12065 -0.3048)
			(end 0.67945 -0.3048)
			(stroke
				(width 0.1)
				(type default)
			)
			(layer "F.Fab")
		)
		(fp_line
			(start 0.67945 -0.3048)
			(end 0.67945 0.3048)
			(stroke
				(width 0.1)
				(type default)
			)
			(layer "F.Fab")
		)
		(fp_line
			(start -0.67945 -0.305054)
			(end -0.12065 -0.305054)
			(stroke
				(width 0.1)
				(type default)
			)
			(layer "F.Fab")
		)
		(fp_line
			(start -0.12065 -0.305054)
			(end -0.12065 -0.2794)
			(stroke
				(width 0.1)
				(type default)
			)
			(layer "F.Fab")
		)
		(pad "1" smd circle
			(at -0.40005 0 270)
			(size 0 0)
			(layers "F.Cu" "F.Mask" "F.Paste")
			(net "P12V_OCP_UV_1")
		)
		(pad "2" smd circle
			(at 0.40005 0 270)
			(size 0 0)
			(layers "F.Cu" "F.Mask" "F.Paste")
			(net "P12V_OCP_OV_1")
		)
	)
	(footprint ""
		(layer "F.Cu")
		(at 364.84179 -392.1252)
		(property "Reference" "R1119"
			(at 0 0 0)
			(layer "F.SilkS")
			(hide yes)
			(effects
				(font
					(size 1.27 1.27)
				)
			)
		)
		(property "Value" ""
			(at 0 0 0)
			(layer "F.Fab")
			(effects
				(font
					(size 1.27 1.27)
				)
			)
		)
		(duplicate_pad_numbers_are_jumpers no)
		(fp_line
			(start -0.32512 -0.175006)
			(end 0.32512 -0.175006)
			(stroke
				(width 0.1)
				(type default)
			)
			(layer "F.Fab")
		)
		(fp_line
			(start -0.32512 0.175006)
			(end -0.32512 -0.175006)
			(stroke
				(width 0.1)
				(type default)
			)
			(layer "F.Fab")
		)
		(fp_line
			(start 0.32512 -0.175006)
			(end 0.32512 0.175006)
			(stroke
				(width 0.1)
				(type default)
			)
			(layer "F.Fab")
		)
		(fp_line
			(start 0.32512 0.175006)
			(end -0.32512 0.175006)
			(stroke
				(width 0.1)
				(type default)
			)
			(layer "F.Fab")
		)
		(pad "1" smd rect
			(at -0.2667 0)
			(size 0.3048 0.381)
			(layers "F.Cu" "F.Mask" "F.Paste")
			(net "P1V8_CPU0_RT_1D")
		)
		(pad "2" smd rect
			(at 0.2667 0 180)
			(size 0.3048 0.381)
			(layers "F.Cu" "F.Mask" "F.Paste")
			(net "TEST2_RT_CPU0_P3")
		)
	)
	(footprint ""
		(layer "F.Cu")
		(at 369.687094 -403.603206 -90)
		(property "Reference" "R1121"
			(at 0 0 270)
			(layer "F.SilkS")
			(hide yes)
			(effects
				(font
					(size 1.27 1.27)
				)
			)
		)
		(property "Value" ""
			(at 0 0 270)
			(layer "F.Fab")
			(effects
				(font
					(size 1.27 1.27)
				)
			)
		)
		(duplicate_pad_numbers_are_jumpers no)
		(fp_line
			(start -0.32512 0.175006)
			(end -0.32512 -0.175006)
			(stroke
				(width 0.1)
				(type default)
			)
			(layer "F.Fab")
		)
		(fp_line
			(start 0.32512 0.175006)
			(end -0.32512 0.175006)
			(stroke
				(width 0.1)
				(type default)
			)
			(layer "F.Fab")
		)
		(fp_line
			(start -0.32512 -0.175006)
			(end 0.32512 -0.175006)
			(stroke
				(width 0.1)
				(type default)
			)
			(layer "F.Fab")
		)
		(fp_line
			(start 0.32512 -0.175006)
			(end 0.32512 0.175006)
			(stroke
				(width 0.1)
				(type default)
			)
			(layer "F.Fab")
		)
		(pad "1" smd rect
			(at -0.2667 0 270)
			(size 0.3048 0.381)
			(layers "F.Cu" "F.Mask" "F.Paste")
			(net "JTAG_TEST_MODE_RT_CPU0_P3")
		)
		(pad "2" smd rect
			(at 0.2667 0 90)
			(size 0.3048 0.381)
			(layers "F.Cu" "F.Mask" "F.Paste")
			(net "GND")
		)
	)
)
